# S9S_MB_2U (Grand Teton) — schematic netlist excerpt (pin names and nets, part order shuffled) for the footprints in the layout excerpt that follows; sources: Cadence DE-HDL packaged netlist, KiCad conversion of 03242023_DA0F0TMBIJ0_F0T_Motherboard_J_brd_V01_OCP.brd

PR4014  Q_RES  49.9 1% CHIP  pkg 0603LF  page 242 : A = P12V_AUX ; B = P12V_SCM_AVIN_PD
PR3989  Q_RES  0 5% CHIP  pkg 0402LF  page 303 : A = HSC_SCREF ; B = HSC_SCREF_4

(kicad_pcb
	(version 20260206)
	(generator "pcbnew")
	(generator_version "10.0")
	(general
		(thickness 1.6)
		(legacy_teardrops no)
	)
	(paper "A4")
	(title_block
		(title "03242023_DA0F0TMBIJ0_F0T_Motherboard_J_brd_V01_OCP.brd")
		(comment 1 "Grand Teton / footprints 4035-4036 of 6105")
	)
	(layers
		(0 "F.Cu" signal "TOP")
		(4 "In1.Cu" signal "GND")
		(6 "In2.Cu" signal "IN1")
		(8 "In3.Cu" signal "GND1")
		(10 "In4.Cu" signal "IN2")
		(12 "In5.Cu" signal "GND2")
		(14 "In6.Cu" signal "IN3")
		(16 "In7.Cu" signal "GND3")
		(18 "In8.Cu" signal "VCC")
		(20 "In9.Cu" signal "VCC1")
		(22 "In10.Cu" signal "GND4")
		(24 "In11.Cu" signal "IN4")
		(26 "In12.Cu" signal "GND5")
		(28 "In13.Cu" signal "IN5")
		(30 "In14.Cu" signal "GND6")
		(32 "In15.Cu" signal "IN6")
		(34 "In16.Cu" signal "GND7")
		(2 "B.Cu" signal "BOTTOM")
		(9 "F.Adhes" user "F.Adhesive")
		(11 "B.Adhes" user "B.Adhesive")
		(13 "F.Paste" user "Package Geometry/Pastemask Top")
		(15 "B.Paste" user "Package Geometry/Pastemask Bottom")
		(5 "F.SilkS" user "Ref Des/Silkscreen Top")
		(7 "B.SilkS" user "Ref Des/Silkscreen Bottom")
		(1 "F.Mask" user "Board Geometry/Soldermask Top")
		(3 "B.Mask" user "Board Geometry/Soldermask Bottom")
		(17 "Dwgs.User" user "User.Drawings")
		(19 "Cmts.User" user "User.Comments")
		(21 "Eco1.User" user "User.Eco1")
		(23 "Eco2.User" user "User.Eco2")
		(25 "Edge.Cuts" user "Board Geometry/Outline")
		(27 "Margin" user)
		(31 "F.CrtYd" user "Package Geometry/Place Bound Top")
		(29 "B.CrtYd" user "Package Geometry/Place Bound Bottom")
		(35 "F.Fab" user "Ref Des/Assembly Top")
		(33 "B.Fab" user "Ref Des/Assembly Bottom")
	)
	(footprint ""
		(layer "F.Cu")
		(at 174.635922 -24.601932)
		(property "Reference" "PR4014"
			(at 0 0 0)
			(layer "F.SilkS")
			(hide yes)
			(effects
				(font
					(size 1.27 1.27)
				)
			)
		)
		(property "Value" ""
			(at 0 0 0)
			(layer "F.Fab")
			(effects
				(font
					(size 1.27 1.27)
				)
			)
		)
		(duplicate_pad_numbers_are_jumpers no)
		(fp_line
			(start -1.2954 -0.5842)
			(end 1.2954 -0.5842)
			(stroke
				(width 0.1524)
				(type default)
			)
			(layer "F.SilkS")
		)
		(fp_line
			(start -1.2954 0.5842)
			(end -1.2954 -0.5842)
			(stroke
				(width 0.1524)
				(type default)
			)
			(layer "F.SilkS")
		)
		(fp_line
			(start 1.2954 -0.5842)
			(end 1.2954 0.5842)
			(stroke
				(width 0.1524)
				(type default)
			)
			(layer "F.SilkS")
		)
		(fp_line
			(start 1.2954 0.5842)
			(end -1.2954 0.5842)
			(stroke
				(width 0.1524)
				(type default)
			)
			(layer "F.SilkS")
		)
		(fp_line
			(start -1.1938 -0.406654)
			(end -0.8636 -0.406654)
			(stroke
				(width 0.1)
				(type default)
			)
			(layer "F.Fab")
		)
		(fp_line
			(start -1.1938 0.4064)
			(end -1.1938 -0.406654)
			(stroke
				(width 0.1)
				(type default)
			)
			(layer "F.Fab")
		)
		(fp_line
			(start -0.8636 -0.4572)
			(end 0.8636 -0.4572)
			(stroke
				(width 0.1)
				(type default)
			)
			(layer "F.Fab")
		)
		(fp_line
			(start -0.8636 -0.406654)
			(end -0.8636 -0.4572)
			(stroke
				(width 0.1)
				(type default)
			)
			(layer "F.Fab")
		)
		(fp_line
			(start -0.8636 0.4064)
			(end -1.1938 0.4064)
			(stroke
				(width 0.1)
				(type default)
			)
			(layer "F.Fab")
		)
		(fp_line
			(start -0.8636 0.4318)
			(end -0.8636 0.4064)
			(stroke
				(width 0.1)
				(type default)
			)
			(layer "F.Fab")
		)
		(fp_line
			(start -0.8636 0.4572)
			(end -0.8636 0.4318)
			(stroke
				(width 0.1)
				(type default)
			)
			(layer "F.Fab")
		)
		(fp_line
			(start 0.8636 -0.4572)
			(end 0.8636 -0.406654)
			(stroke
				(width 0.1)
				(type default)
			)
			(layer "F.Fab")
		)
		(fp_line
			(start 0.8636 -0.406654)
			(end 1.1938 -0.406654)
			(stroke
				(width 0.1)
				(type default)
			)
			(layer "F.Fab")
		)
		(fp_line
			(start 0.8636 0.4064)
			(end 0.8636 0.4572)
			(stroke
				(width 0.1)
				(type default)
			)
			(layer "F.Fab")
		)
		(fp_line
			(start 0.8636 0.4572)
			(end -0.8636 0.4572)
			(stroke
				(width 0.1)
				(type default)
			)
			(layer "F.Fab")
		)
		(fp_line
			(start 1.1938 -0.406654)
			(end 1.1938 0.4064)
			(stroke
				(width 0.1)
				(type default)
			)
			(layer "F.Fab")
		)
		(fp_line
			(start 1.1938 0.4064)
			(end 0.8636 0.4064)
			(stroke
				(width 0.1)
				(type default)
			)
			(layer "F.Fab")
		)
		(pad "1" smd rect
			(at -0.7366 0 270)
			(size 0.7112 0.8128)
			(layers "F.Cu" "F.Mask" "F.Paste")
			(net "P12V_AUX")
		)
		(pad "2" smd rect
			(at 0.7366 0 270)
			(size 0.7112 0.8128)
			(layers "F.Cu" "F.Mask" "F.Paste")
			(net "P12V_SCM_AVIN_PD")
		)
	)
	(footprint ""
		(layer "F.Cu")
		(at 226.733608 -408.887422)
		(property "Reference" "PR3989"
			(at 0 0 0)
			(layer "F.SilkS")
			(hide yes)
			(effects
				(font
					(size 1.27 1.27)
				)
			)
		)
		(property "Value" ""
			(at 0 0 0)
			(layer "F.Fab")
			(effects
				(font
					(size 1.27 1.27)
				)
			)
		)
		(duplicate_pad_numbers_are_jumpers no)
		(fp_line
			(start -0.7874 -0.4064)
			(end 0.7874 -0.4064)
			(stroke
				(width 0.1524)
				(type default)
			)
			(layer "F.SilkS")
		)
		(fp_line
			(start -0.7874 0.4064)
			(end -0.7874 -0.4064)
			(stroke
				(width 0.1524)
				(type default)
			)
			(layer "F.SilkS")
		)
		(fp_line
			(start 0.7874 -0.4064)
			(end 0.7874 0.4064)
			(stroke
				(width 0.1524)
				(type default)
			)
			(layer "F.SilkS")
		)
		(fp_line
			(start 0.7874 0.4064)
			(end -0.7874 0.4064)
			(stroke
				(width 0.1524)
				(type default)
			)
			(layer "F.SilkS")
		)
		(fp_line
			(start -0.67945 -0.305054)
			(end -0.12065 -0.305054)
			(stroke
				(width 0.1)
				(type default)
			)
			(layer "F.Fab")
		)
		(fp_line
			(start -0.67945 0.3048)
			(end -0.67945 -0.305054)
			(stroke
				(width 0.1)
				(type default)
			)
			(layer "F.Fab")
		)
		(fp_line
			(start -0.12065 -0.305054)
			(end -0.12065 -0.2794)
			(stroke
				(width 0.1)
				(type default)
			)
			(layer "F.Fab")
		)
		(fp_line
			(start -0.12065 -0.2794)
			(end 0.12065 -0.2794)
			(stroke
				(width 0.1)
				(type default)
			)
			(layer "F.Fab")
		)
		(fp_line
			(start -0.12065 0.2794)
			(end -0.12065 0.3048)
			(stroke
				(width 0.1)
				(type default)
			)
			(layer "F.Fab")
		)
		(fp_line
			(start -0.12065 0.3048)
			(end -0.67945 0.3048)
			(stroke
				(width 0.1)
				(type default)
			)
			(layer "F.Fab")
		)
		(fp_line
			(start 0.120396 0.2794)
			(end -0.12065 0.2794)
			(stroke
				(width 0.1)
				(type default)
			)
			(layer "F.Fab")
		)
		(fp_line
			(start 0.120396 0.3048)
			(end 0.120396 0.2794)
			(stroke
				(width 0.1)
				(type default)
			)
			(layer "F.Fab")
		)
		(fp_line
			(start 0.12065 -0.3048)
			(end 0.67945 -0.3048)
			(stroke
				(width 0.1)
				(type default)
			)
			(layer "F.Fab")
		)
		(fp_line
			(start 0.12065 -0.2794)
			(end 0.12065 -0.3048)
			(stroke
				(width 0.1)
				(type default)
			)
			(layer "F.Fab")
		)
		(fp_line
			(start 0.67945 -0.3048)
			(end 0.67945 0.3048)
			(stroke
				(width 0.1)
				(type default)
			)
			(layer "F.Fab")
		)
		(fp_line
			(start 0.67945 0.3048)
			(end 0.120396 0.3048)
			(stroke
				(width 0.1)
				(type default)
			)
			(layer "F.Fab")
		)
		(pad "1" smd circle
			(at -0.40005 0)
			(size 0 0)
			(layers "F.Cu" "F.Mask" "F.Paste")
			(net "HSC_SCREF")
		)
		(pad "2" smd circle
			(at 0.40005 0)
			(size 0 0)
			(layers "F.Cu" "F.Mask" "F.Paste")
			(net "HSC_SCREF_4")
		)
	)
)
